# BASEBOARD_FAB2 (Tioga Pass) — schematic netlist excerpt (pin names and nets, part order shuffled) for the footprints in the layout excerpt that follows; sources: Cadence DE-HDL packaged netlist, KiCad conversion of Wiwynn_Tioga_Pass_MB.brd

CR9W1  DIODE  BAT54WS IC  pkg SMLF  page 155 : C = SPA_5V_SIN_SW ; A = SPA_5V_SIN_SW_D
R4C13  RES  68.1K 1% EMPTY  pkg 0402  page 205 : A = VR_PVSA_CPU0_OCSET ; B = GND

(kicad_pcb
	(version 20260206)
	(generator "pcbnew")
	(generator_version "10.0")
	(general
		(thickness 1.6)
		(legacy_teardrops no)
	)
	(paper "A4")
	(title_block
		(title "Wiwynn_Tioga_Pass_MB.brd")
		(comment 1 "Tioga Pass / footprints 1610-1611 of 4770")
	)
	(layers
		(0 "F.Cu" signal "TOP")
		(4 "In1.Cu" signal "L2GND")
		(6 "In2.Cu" signal "L3")
		(8 "In3.Cu" signal "L4GND")
		(10 "In4.Cu" signal "L5")
		(12 "In5.Cu" signal "L6GND")
		(14 "In6.Cu" signal "L7VCC")
		(16 "In7.Cu" signal "L8VCC")
		(18 "In8.Cu" signal "L9GND")
		(20 "In9.Cu" signal "L10")
		(22 "In10.Cu" signal "L11GND")
		(24 "In11.Cu" signal "L12")
		(26 "In12.Cu" signal "L13GND")
		(2 "B.Cu" signal "BOTTOM")
		(9 "F.Adhes" user "F.Adhesive")
		(11 "B.Adhes" user "B.Adhesive")
		(13 "F.Paste" user "Package Geometry/Pastemask Top")
		(15 "B.Paste" user "Package Geometry/Pastemask Bottom")
		(5 "F.SilkS" user "Ref Des/Silkscreen Top")
		(7 "B.SilkS" user "Ref Des/Silkscreen Bottom")
		(1 "F.Mask" user "Board Geometry/Soldermask Top")
		(3 "B.Mask" user "Board Geometry/Soldermask Bottom")
		(17 "Dwgs.User" user "User.Drawings")
		(19 "Cmts.User" user "User.Comments")
		(21 "Eco1.User" user "User.Eco1")
		(23 "Eco2.User" user "User.Eco2")
		(25 "Edge.Cuts" user "Board Geometry/Outline")
		(27 "Margin" user)
		(31 "F.CrtYd" user "Package Geometry/Place Bound Top")
		(29 "B.CrtYd" user "Package Geometry/Place Bound Bottom")
		(35 "F.Fab" user "Ref Des/Assembly Top")
		(33 "B.Fab" user "Ref Des/Assembly Bottom")
	)
	(footprint ""
		(layer "F.Cu")
		(at 489.3056 -153.3398)
		(property "Reference" "CR9W1"
			(at 1.06934 -0.39116 270)
			(unlocked yes)
			(layer "F.SilkS")
			(effects
				(font
					(size 0.4064 0.254)
					(thickness 0.1524)
				)
				(justify left)
			)
		)
		(property "Value" ""
			(at 0 0 0)
			(layer "F.Fab")
			(effects
				(font
					(size 1.27 1.27)
				)
			)
		)
		(duplicate_pad_numbers_are_jumpers no)
		(fp_line
			(start -1.8161 1.664462)
			(end -1.335278 0.831596)
			(stroke
				(width 0.1524)
				(type default)
			)
			(layer "F.SilkS")
		)
		(fp_line
			(start -1.335278 -0.291846)
			(end -1.335278 0.831596)
			(stroke
				(width 0.1524)
				(type default)
			)
			(layer "F.SilkS")
		)
		(fp_line
			(start -1.335278 0.831596)
			(end -0.854456 1.664462)
			(stroke
				(width 0.1524)
				(type default)
			)
			(layer "F.SilkS")
		)
		(fp_line
			(start -1.335278 1.664462)
			(end -1.8161 1.664462)
			(stroke
				(width 0.1524)
				(type default)
			)
			(layer "F.SilkS")
		)
		(fp_line
			(start -1.335278 2.576068)
			(end -1.335278 1.664462)
			(stroke
				(width 0.1524)
				(type default)
			)
			(layer "F.SilkS")
		)
		(fp_line
			(start -0.854456 0.831596)
			(end -1.8161 0.831596)
			(stroke
				(width 0.1524)
				(type default)
			)
			(layer "F.SilkS")
		)
		(fp_line
			(start -0.854456 1.664462)
			(end -1.335278 1.664462)
			(stroke
				(width 0.1524)
				(type default)
			)
			(layer "F.SilkS")
		)
		(fp_poly
			(pts
				(xy -0.67437 0.24384) (xy -0.67437 2.04216) (xy 0.67437 2.04216) (xy 0.67437 0.24384)
			)
			(stroke
				(width 0)
				(type default)
			)
			(fill no)
			(layer "F.CrtYd")
		)
		(fp_line
			(start -1.8161 1.664462)
			(end -1.335278 0.831596)
			(stroke
				(width 0.1)
				(type default)
			)
			(layer "F.Fab")
		)
		(fp_line
			(start -1.335278 0.831596)
			(end -1.335278 -0.291846)
			(stroke
				(width 0.1)
				(type default)
			)
			(layer "F.Fab")
		)
		(fp_line
			(start -1.335278 0.831596)
			(end -0.854456 1.664462)
			(stroke
				(width 0.1)
				(type default)
			)
			(layer "F.Fab")
		)
		(fp_line
			(start -1.335278 1.664462)
			(end -1.335278 2.576068)
			(stroke
				(width 0.1)
				(type default)
			)
			(layer "F.Fab")
		)
		(fp_line
			(start -0.854456 0.831596)
			(end -1.8161 0.831596)
			(stroke
				(width 0.1)
				(type default)
			)
			(layer "F.Fab")
		)
		(fp_line
			(start -0.854456 1.664462)
			(end -1.8161 1.664462)
			(stroke
				(width 0.1)
				(type default)
			)
			(layer "F.Fab")
		)
		(fp_line
			(start -0.67437 0.24384)
			(end -0.67437 2.04216)
			(stroke
				(width 0.1)
				(type default)
			)
			(layer "F.Fab")
		)
		(fp_line
			(start -0.67437 2.04216)
			(end 0.67437 2.04216)
			(stroke
				(width 0.1)
				(type default)
			)
			(layer "F.Fab")
		)
		(fp_line
			(start 0.67437 0.24384)
			(end -0.67437 0.24384)
			(stroke
				(width 0.1)
				(type default)
			)
			(layer "F.Fab")
		)
		(fp_line
			(start 0.67437 2.04216)
			(end 0.67437 0.24384)
			(stroke
				(width 0.1)
				(type default)
			)
			(layer "F.Fab")
		)
		(pad "1" smd rect
			(at 0 0)
			(size 0.4064 1.016)
			(layers "F.Cu" "F.Mask" "F.Paste")
			(net "SPA_5V_SIN_SW")
		)
		(pad "2" smd rect
			(at 0 2.286)
			(size 0.4064 1.016)
			(layers "F.Cu" "F.Mask" "F.Paste")
			(net "SPA_5V_SIN_SW_D")
		)
	)
	(footprint ""
		(layer "F.Cu")
		(at 193.662808 -96.707452 -90)
		(property "Reference" "R4C13"
			(at 0 0 270)
			(layer "F.SilkS")
			(hide yes)
			(effects
				(font
					(size 1.27 1.27)
				)
			)
		)
		(property "Value" ""
			(at 0 0 270)
			(layer "F.Fab")
			(effects
				(font
					(size 1.27 1.27)
				)
			)
		)
		(duplicate_pad_numbers_are_jumpers no)
		(fp_poly
			(pts
				(xy -0.2794 -0.1016) (xy 0.2794 -0.1016) (xy 0.2794 0.9906) (xy -0.2794 0.9906)
			)
			(stroke
				(width 0)
				(type default)
			)
			(fill no)
			(layer "F.CrtYd")
		)
		(fp_line
			(start -0.2794 0.9906)
			(end 0.2794 0.9906)
			(stroke
				(width 0.1)
				(type default)
			)
			(layer "F.Fab")
		)
		(fp_line
			(start 0.2794 0.9906)
			(end 0.2794 -0.1016)
			(stroke
				(width 0.1)
				(type default)
			)
			(layer "F.Fab")
		)
		(fp_line
			(start -0.2794 -0.1016)
			(end -0.2794 0.9906)
			(stroke
				(width 0.1)
				(type default)
			)
			(layer "F.Fab")
		)
		(fp_line
			(start 0.2794 -0.1016)
			(end -0.2794 -0.1016)
			(stroke
				(width 0.1)
				(type default)
			)
			(layer "F.Fab")
		)
		(pad "1" smd rect
			(at 0 0 270)
			(size 0.508 0.508)
			(layers "F.Cu" "F.Mask" "F.Paste")
			(net "VR_PVSA_CPU0_OCSET")
		)
		(pad "2" smd rect
			(at 0 0.889 270)
			(size 0.508 0.508)
			(layers "F.Cu" "F.Mask" "F.Paste")
			(net "GND")
		)
		(zone
			(layer "F.Cu")
			(hatch none 0.5)
			(connect_pads
				(clearance 0)
			)
			(min_thickness 0.25)
			(keepout
				(tracks not_allowed)
				(vias allowed)
				(pads allowed)
				(copperpour not_allowed)
				(footprints allowed)
			)
			(placement
				(enabled no)
				(sheetname "")
			)
			(fill
				(thermal_gap 0.5)
				(thermal_bridge_width 0.5)
				(island_removal_mode 0)
			)
			(polygon
				(pts
					(xy 193.027808 -96.961452) (xy 193.027808 -96.453452) (xy 193.408808 -96.453452) (xy 193.408808 -96.961452)
				)
			)
		)
		(zone
			(layer "F.Cu")
			(hatch none 0.5)
			(connect_pads
				(clearance 0)
			)
			(min_thickness 0.25)
			(keepout
				(tracks allowed)
				(vias not_allowed)
				(pads allowed)
				(copperpour not_allowed)
				(footprints allowed)
			)
			(placement
				(enabled no)
				(sheetname "")
			)
			(fill
				(thermal_gap 0.5)
				(thermal_bridge_width 0.5)
				(island_removal_mode 0)
			)
			(polygon
				(pts
					(xy 193.408808 -96.961452) (xy 193.408808 -96.453452) (xy 193.027808 -96.453452) (xy 193.027808 -96.961452)
				)
			)
		)
	)
)
